(kicad_pcb
	(version 20241229)
	(generator "pcbnew")
	(generator_version "9.0")
	(general
		(thickness 1.6296)
		(legacy_teardrops no)
	)
	(paper "A3")
	(title_block
		(title "Thunderbolt to 10GbE adapter")
		(date "2026-04-21")
		(rev "1.1.0")
		(company "Antmicro Ltd")
		(comment 1 "www.antmicro.com")
		(comment 9 "footprints 28-31 of 703")
	)
	(layers
		(0 "F.Cu" signal)
		(4 "In1.Cu" signal)
		(6 "In2.Cu" signal)
		(8 "In3.Cu" signal)
		(10 "In4.Cu" signal)
		(12 "In5.Cu" signal)
		(14 "In6.Cu" signal)
		(2 "B.Cu" signal)
		(9 "F.Adhes" user "F.Adhesive")
		(11 "B.Adhes" user "B.Adhesive")
		(13 "F.Paste" user)
		(15 "B.Paste" user)
		(5 "F.SilkS" user "F.Silkscreen")
		(7 "B.SilkS" user "B.Silkscreen")
		(1 "F.Mask" user)
		(3 "B.Mask" user)
		(17 "Dwgs.User" user "User.Drawings")
		(19 "Cmts.User" user "User.Comments")
		(21 "Eco1.User" user "User.Eco1")
		(23 "Eco2.User" user "User.Eco2")
		(25 "Edge.Cuts" user)
		(27 "Margin" user)
		(31 "F.CrtYd" user "F.Courtyard")
		(29 "B.CrtYd" user "B.Courtyard")
		(35 "F.Fab" user)
		(33 "B.Fab" user)
	)
	(footprint "antmicro-footprints:R_0402_1005Metric"
		(layer "F.Cu")
		(at 151.550002 113.150002)
		(descr "Resistor SMD 0402")
		(tags "resistor SMD 0402")
		(property "Reference" "R93"
			(at 14.149998 17.25 0)
			(layer "F.SilkS")
			(effects
				(font
					(size 0.7 0.7)
					(thickness 0.15)
				)
			)
		)
		(property "Value" "R_0R_0402"
			(at -1.011843 1.772047 0)
			(layer "F.Fab")
			(effects
				(font
					(size 0.7 0.7)
					(thickness 0.15)
				)
				(justify left bottom)
			)
		)
		(property "Datasheet" "https://industrial.panasonic.com/cdbs/www-data/pdf/RDA0000/AOA0000C301.pdf"
			(at 0 0 0)
			(layer "F.Fab")
			(hide yes)
			(effects
				(font
					(size 1.27 1.27)
					(thickness 0.15)
				)
			)
		)
		(property "Description" "SMD Chip Resistor, Jumper, 0 ohm, 100 mW, 0402 [1005 Metric], Thick Film, General Purpose"
			(at 0 0 0)
			(layer "F.Fab")
			(hide yes)
			(effects
				(font
					(size 1.27 1.27)
					(thickness 0.15)
				)
			)
		)
		(property "MPN" "ERJ2GE0R00X"
			(at 0 0 0)
			(unlocked yes)
			(layer "F.Fab")
			(hide yes)
			(effects
				(font
					(size 1 1)
					(thickness 0.15)
				)
			)
		)
		(property "Manufacturer" "Panasonic"
			(at 0 0 0)
			(unlocked yes)
			(layer "F.Fab")
			(hide yes)
			(effects
				(font
					(size 1 1)
					(thickness 0.15)
				)
			)
		)
		(property "License" "Apache-2.0"
			(at 0 0 0)
			(unlocked yes)
			(layer "F.Fab")
			(hide yes)
			(effects
				(font
					(size 1 1)
					(thickness 0.15)
				)
			)
		)
		(property "Author" "Antmicro"
			(at 0 0 0)
			(unlocked yes)
			(layer "F.Fab")
			(hide yes)
			(effects
				(font
					(size 1 1)
					(thickness 0.15)
				)
			)
		)
		(property "Val" "0R"
			(at 0 0 0)
			(unlocked yes)
			(layer "F.Fab")
			(hide yes)
			(effects
				(font
					(size 1 1)
					(thickness 0.15)
				)
			)
		)
		(property "Tolerance" "~"
			(at 0 0 0)
			(unlocked yes)
			(layer "F.Fab")
			(hide yes)
			(effects
				(font
					(size 1 1)
					(thickness 0.15)
				)
			)
		)
		(property "Current" "1A"
			(at 0 0 0)
			(unlocked yes)
			(layer "F.Fab")
			(hide yes)
			(effects
				(font
					(size 1 1)
					(thickness 0.15)
				)
			)
		)
		(sheetname "/X710 DCDC converters/")
		(sheetfile "DCDC_converters_X710.kicad_sch")
		(attr smd)
		(fp_rect
			(start -0.925 -0.47)
			(end 0.925 0.47)
			(stroke
				(width 0.05)
				(type default)
			)
			(fill no)
			(layer "F.CrtYd")
		)
		(fp_rect
			(start -0.5 -0.25)
			(end 0.5 0.25)
			(stroke
				(width 0.15)
				(type solid)
			)
			(fill no)
			(layer "F.Fab")
		)
		(fp_text user "License: Apache-2.0"
			(at -0.95 5.169 0)
			(layer "F.Fab")
			(effects
				(font
					(size 0.7 0.7)
					(thickness 0.15)
				)
				(justify left bottom)
			)
		)
		(fp_text user "Author: Antmicro"
			(at -0.95 4.169 0)
			(layer "F.Fab")
			(effects
				(font
					(size 0.7 0.7)
					(thickness 0.15)
				)
				(justify left bottom)
			)
		)
		(fp_text user "${REFERENCE}"
			(at -0.95 3.168 0)
			(layer "F.Fab")
			(effects
				(font
					(size 0.7 0.7)
					(thickness 0.15)
				)
				(justify left bottom)
			)
		)
		(pad "1" smd roundrect
			(at -0.48 0)
			(size 0.59 0.64)
			(layers "F.Cu" "F.Mask" "F.Paste")
			(roundrect_rratio 0.25)
			(net 379 "/X710 DCDC converters/VCCD_PG")
			(pintype "passive")
		)
		(pad "2" smd roundrect
			(at 0.48 0)
			(size 0.59 0.64)
			(layers "F.Cu" "F.Mask" "F.Paste")
			(roundrect_rratio 0.25)
			(net 384 "/X710 DCDC converters/1V88_EN")
			(pintype "passive")
		)
	)
	(footprint "antmicro-footprints:R_0603_1608Metric"
		(layer "F.Cu")
		(at 137.870002 91.25)
		(descr "Resistor SMD 0603")
		(tags "resistor SMD 0603")
		(property "Reference" "R108"
			(at 37.144997 -9.199999 0)
			(layer "F.SilkS")
			(effects
				(font
					(size 0.7 0.7)
					(thickness 0.15)
				)
			)
		)
		(property "Value" "R_0R_22.4A_0603"
			(at 0 1.6 0)
			(layer "F.Fab")
			(effects
				(font
					(size 0.7 0.7)
					(thickness 0.15)
				)
				(justify left bottom)
			)
		)
		(property "Datasheet" "https://fscdn.rohm.com/en/products/databook/datasheet/passive/resistor/chip_resistor/pmr-jpw-e.pdf"
			(at 0 0 0)
			(layer "F.Fab")
			(hide yes)
			(effects
				(font
					(size 1.27 1.27)
					(thickness 0.15)
				)
			)
		)
		(property "Description" "SMD Chip Resistor"
			(at 0 0 0)
			(layer "F.Fab")
			(hide yes)
			(effects
				(font
					(size 1.27 1.27)
					(thickness 0.15)
				)
			)
		)
		(property "MPN" "PMR03EZPJ000"
			(at 0 0 0)
			(unlocked yes)
			(layer "F.Fab")
			(hide yes)
			(effects
				(font
					(size 1 1)
					(thickness 0.15)
				)
			)
		)
		(property "Manufacturer" "ROHM Semiconductor"
			(at 0 0 0)
			(unlocked yes)
			(layer "F.Fab")
			(hide yes)
			(effects
				(font
					(size 1 1)
					(thickness 0.15)
				)
			)
		)
		(property "Val" "0R"
			(at 0 0 0)
			(unlocked yes)
			(layer "F.Fab")
			(hide yes)
			(effects
				(font
					(size 1 1)
					(thickness 0.15)
				)
			)
		)
		(property "Max. Curr." "22.4A"
			(at 0 0 0)
			(unlocked yes)
			(layer "F.Fab")
			(hide yes)
			(effects
				(font
					(size 1 1)
					(thickness 0.15)
				)
			)
		)
		(property "Author" "Antmicro"
			(at 0 0 0)
			(unlocked yes)
			(layer "F.Fab")
			(hide yes)
			(effects
				(font
					(size 1 1)
					(thickness 0.15)
				)
			)
		)
		(property "License" "Apache-2.0"
			(at 0 0 0)
			(unlocked yes)
			(layer "F.Fab")
			(hide yes)
			(effects
				(font
					(size 1 1)
					(thickness 0.15)
				)
			)
		)
		(property "Tolerance" "template_tolerance"
			(at 0 0 0)
			(unlocked yes)
			(layer "F.Fab")
			(hide yes)
			(effects
				(font
					(size 1 1)
					(thickness 0.15)
				)
			)
		)
		(sheetname "/X710 DCDC converters/")
		(sheetfile "DCDC_converters_X710.kicad_sch")
		(attr smd)
		(fp_line
			(start -0.15 -0.4)
			(end 0.15 -0.4)
			(stroke
				(width 0.15)
				(type solid)
			)
			(layer "F.SilkS")
		)
		(fp_line
			(start -0.15 0.4)
			(end 0.15 0.4)
			(stroke
				(width 0.15)
				(type solid)
			)
			(layer "F.SilkS")
		)
		(fp_rect
			(start -1.25 -0.65)
			(end 1.25 0.65)
			(stroke
				(width 0.05)
				(type solid)
			)
			(fill no)
			(layer "F.CrtYd")
		)
		(fp_rect
			(start -0.8 -0.4)
			(end 0.8 0.4)
			(stroke
				(width 0.15)
				(type solid)
			)
			(fill no)
			(layer "F.Fab")
		)
		(fp_text user "Author: Antmicro"
			(at -1.25 4.9 0)
			(layer "F.Fab")
			(effects
				(font
					(size 0.7 0.7)
					(thickness 0.15)
				)
				(justify left bottom)
			)
		)
		(fp_text user "License: Apache-2.0"
			(at -1.25 5.9 0)
			(layer "F.Fab")
			(effects
				(font
					(size 0.7 0.7)
					(thickness 0.15)
				)
				(justify left bottom)
			)
		)
		(fp_text user "${REFERENCE}"
			(at -1.25 3.898 0)
			(layer "F.Fab")
			(effects
				(font
					(size 0.7 0.7)
					(thickness 0.15)
				)
				(justify left bottom)
			)
		)
		(pad "1" smd roundrect
			(at -0.7 0)
			(size 0.8 1)
			(layers "F.Cu" "F.Mask" "F.Paste")
			(roundrect_rratio 0.2)
			(net 334 "/X710 DCDC converters/+3V3_OUT")
			(pintype "passive")
		)
		(pad "2" smd roundrect
			(at 0.7 0)
			(size 0.8 1)
			(layers "F.Cu" "F.Mask" "F.Paste")
			(roundrect_rratio 0.2)
			(net 7 "+3V3")
			(pintype "passive")
		)
	)
	(footprint "antmicro-footprints:SOIC-8_5.3x5.3x2mm_P1.27mm"
		(layer "F.Cu")
		(at 147.8 122.2 90)
		(descr "8-Pin SOIC 208-mil")
		(property "Reference" "U8"
			(at 3.3 4 90)
			(layer "F.SilkS")
			(effects
				(font
					(size 0.7 0.7)
					(thickness 0.15)
				)
				(justify left bottom)
			)
		)
		(property "Value" "MX25L8006EM2I-12G"
			(at 0 3.8 90)
			(layer "F.Fab")
			(effects
				(font
					(size 0.7 0.7)
					(thickness 0.15)
				)
				(justify left bottom)
			)
		)
		(property "Datasheet" "https://www.macronix.com/Lists/Datasheet/Attachments/8680/MX25L8006E,%203V,%208Mb,%20v1.6.pdf"
			(at 0 0 90)
			(layer "F.Fab")
			(hide yes)
			(effects
				(font
					(size 1.27 1.27)
					(thickness 0.15)
				)
			)
		)
		(property "Description" "FLASH - NOR Memory IC 8Mbit SPI 86 MHz 8-SOP"
			(at 0 0 90)
			(layer "F.Fab")
			(hide yes)
			(effects
				(font
					(size 1.27 1.27)
					(thickness 0.15)
				)
			)
		)
		(property "MPN" "MX25L8006EM2I-12G"
			(at 0 0 90)
			(unlocked yes)
			(layer "F.Fab")
			(hide yes)
			(effects
				(font
					(size 1 1)
					(thickness 0.15)
				)
			)
		)
		(property "Manufacturer" "Macronix"
			(at 0 0 90)
			(unlocked yes)
			(layer "F.Fab")
			(hide yes)
			(effects
				(font
					(size 1 1)
					(thickness 0.15)
				)
			)
		)
		(property "Author" "Antmicro"
			(at 0 0 90)
			(unlocked yes)
			(layer "F.Fab")
			(hide yes)
			(effects
				(font
					(size 1 1)
					(thickness 0.15)
				)
			)
		)
		(property "License" "Apache-2.0"
			(at 0 0 90)
			(unlocked yes)
			(layer "F.Fab")
			(hide yes)
			(effects
				(font
					(size 1 1)
					(thickness 0.15)
				)
			)
		)
		(sheetname "/TB flash memory/")
		(sheetfile "flash-memory.kicad_sch")
		(attr smd dnp)
		(fp_line
			(start -2.8 -2.641)
			(end -4.4 -2.641)
			(stroke
				(width 0.15)
				(type solid)
			)
			(layer "F.SilkS")
		)
		(fp_circle
			(center -4.85 -1.905)
			(end -4.8 -1.855)
			(stroke
				(width 0.15)
				(type solid)
			)
			(fill yes)
			(layer "F.SilkS")
		)
		(fp_rect
			(start 4.675 -3)
			(end -4.675 3)
			(stroke
				(width 0.05)
				(type solid)
			)
			(fill no)
			(layer "F.CrtYd")
		)
		(fp_line
			(start 2.64 -2.641)
			(end 2.64 2.64)
			(stroke
				(width 0.15)
				(type solid)
			)
			(layer "F.Fab")
		)
		(fp_line
			(start -2.641 -2.641)
			(end 2.64 -2.641)
			(stroke
				(width 0.15)
				(type solid)
			)
			(layer "F.Fab")
		)
		(fp_line
			(start -2.641 -1.371)
			(end -1.371 -2.641)
			(stroke
				(width 0.15)
				(type solid)
			)
			(layer "F.Fab")
		)
		(fp_line
			(start 2.64 2.64)
			(end -2.641 2.64)
			(stroke
				(width 0.15)
				(type solid)
			)
			(layer "F.Fab")
		)
		(fp_line
			(start -2.641 2.64)
			(end -2.641 -2.641)
			(stroke
				(width 0.15)
				(type solid)
			)
			(layer "F.Fab")
		)
		(fp_text user "${REFERENCE}"
			(at -4.675 4.938 90)
			(layer "F.Fab")
			(effects
				(font
					(size 0.7 0.7)
					(thickness 0.15)
				)
				(justify left bottom)
			)
		)
		(fp_text user "Author: Antmicro"
			(at -4.675 5.938 90)
			(layer "F.Fab")
			(effects
				(font
					(size 0.7 0.7)
					(thickness 0.15)
				)
				(justify left bottom)
			)
		)
		(fp_text user "License: Apache-2.0"
			(at -4.675 6.938 90)
			(layer "F.Fab")
			(effects
				(font
					(size 0.7 0.7)
					(thickness 0.15)
				)
				(justify left bottom)
			)
		)
		(pad "1" smd roundrect
			(at -3.601 -1.905 180)
			(size 0.65 1.65)
			(layers "F.Cu" "F.Mask" "F.Paste")
			(roundrect_rratio 0.25)
			(net 359 "/PD and TB DC-DC/TB_FLASH.~{CE}")
			(pinfunction "~{CS}")
			(pintype "input")
		)
		(pad "2" smd roundrect
			(at -3.601 -0.635 180)
			(size 0.65 1.65)
			(layers "F.Cu" "F.Mask" "F.Paste")
			(roundrect_rratio 0.25)
			(net 357 "/PD and TB DC-DC/TB_FLASH.MISO")
			(pinfunction "SO/IO1")
			(pintype "input")
		)
		(pad "3" smd roundrect
			(at -3.601 0.633 180)
			(size 0.65 1.65)
			(layers "F.Cu" "F.Mask" "F.Paste")
			(roundrect_rratio 0.25)
			(net 358 "/TB flash memory/FLASH_WP")
			(pinfunction "~{WP}")
			(pintype "input")
		)
		(pad "4" smd roundrect
			(at -3.601 1.904 180)
			(size 0.65 1.65)
			(layers "F.Cu" "F.Mask" "F.Paste")
			(roundrect_rratio 0.25)
			(net 23 "GND")
			(pinfunction "GND")
			(pintype "power_in")
		)
		(pad "5" smd roundrect
			(at 3.6 1.904 180)
			(size 0.65 1.65)
			(layers "F.Cu" "F.Mask" "F.Paste")
			(roundrect_rratio 0.25)
			(net 398 "/PD and TB DC-DC/TB_FLASH.MOSI")
			(pinfunction "SI/IO0")
			(pintype "input")
		)
		(pad "6" smd roundrect
			(at 3.6 0.633 180)
			(size 0.65 1.65)
			(layers "F.Cu" "F.Mask" "F.Paste")
			(roundrect_rratio 0.25)
			(net 397 "/PD and TB DC-DC/TB_FLASH.CLK")
			(pinfunction "SCLK")
			(pintype "input")
		)
		(pad "7" smd roundrect
			(at 3.6 -0.635 180)
			(size 0.65 1.65)
			(layers "F.Cu" "F.Mask" "F.Paste")
			(roundrect_rratio 0.25)
			(net 370 "/TB flash memory/FLASH_HOLD")
			(pinfunction "~{HOLD}")
			(pintype "input")
		)
		(pad "8" smd roundrect
			(at 3.6 -1.905 180)
			(size 0.65 1.65)
			(layers "F.Cu" "F.Mask" "F.Paste")
			(roundrect_rratio 0.25)
			(net 57 "+3V3_TB")
			(pinfunction "VCC")
			(pintype "power_in")
		)
	)
	(footprint "antmicro-footprints:C_0402_1005Metric"
		(layer "F.Cu")
		(at 133 131.2)
		(descr "Capacitor SMD 0402")
		(tags "capacitor SMD 0402")
		(property "Reference" "C82"
			(at -3.2 0.4 0)
			(layer "F.SilkS")
			(effects
				(font
					(size 0.7 0.7)
					(thickness 0.15)
				)
				(justify left bottom)
			)
		)
		(property "Value" "C_100n_0402"
			(at -1.022927 2.155213 0)
			(layer "F.Fab")
			(effects
				(font
					(size 0.7 0.7)
					(thickness 0.15)
				)
				(justify left bottom)
			)
		)
		(property "Datasheet" "https://www.murata.com/products/productdetail?partno=GRM155R61H104KE14%23"
			(at 0 0 0)
			(layer "F.Fab")
			(hide yes)
			(effects
				(font
					(size 1.27 1.27)
					(thickness 0.15)
				)
			)
		)
		(property "Description" "SMD Multilayer Ceramic Capacitor, 0.1 µF, 50 V, 0402 [1005 Metric], ± 10%, X5R, GRM Series"
			(at 0 0 0)
			(layer "F.Fab")
			(hide yes)
			(effects
				(font
					(size 1.27 1.27)
					(thickness 0.15)
				)
			)
		)
		(property "MPN" "GRM155R61H104KE14D"
			(at 0 0 0)
			(unlocked yes)
			(layer "F.Fab")
			(hide yes)
			(effects
				(font
					(size 1 1)
					(thickness 0.15)
				)
			)
		)
		(property "Manufacturer" "Murata"
			(at 0 0 0)
			(unlocked yes)
			(layer "F.Fab")
			(hide yes)
			(effects
				(font
					(size 1 1)
					(thickness 0.15)
				)
			)
		)
		(property "License" "Apache-2.0"
			(at 0 0 0)
			(unlocked yes)
			(layer "F.Fab")
			(hide yes)
			(effects
				(font
					(size 1 1)
					(thickness 0.15)
				)
			)
		)
		(property "Val" "100n"
			(at 0 0 0)
			(unlocked yes)
			(layer "F.Fab")
			(hide yes)
			(effects
				(font
					(size 1 1)
					(thickness 0.15)
				)
			)
		)
		(property "Voltage" "50V"
			(at 0 0 0)
			(unlocked yes)
			(layer "F.Fab")
			(hide yes)
			(effects
				(font
					(size 1 1)
					(thickness 0.15)
				)
			)
		)
		(property "Dielectric" "X5R"
			(at 0 0 0)
			(unlocked yes)
			(layer "F.Fab")
			(hide yes)
			(effects
				(font
					(size 1 1)
					(thickness 0.15)
				)
			)
		)
		(property "Author" "Antmicro"
			(at 0 0 0)
			(unlocked yes)
			(layer "F.Fab")
			(hide yes)
			(effects
				(font
					(size 1 1)
					(thickness 0.15)
				)
			)
		)
		(sheetname "/TB Controller - Power/")
		(sheetfile "tb-power.kicad_sch")
		(attr smd)
		(fp_rect
			(start -0.925 -0.47)
			(end 0.925 0.47)
			(stroke
				(width 0.05)
				(type default)
			)
			(fill no)
			(layer "F.CrtYd")
		)
		(fp_line
			(start -0.494 -0.25)
			(end 0.504 -0.25)
			(stroke
				(width 0.15)
				(type solid)
			)
			(layer "F.Fab")
		)
		(fp_line
			(start -0.494 0.248)
			(end -0.494 -0.25)
			(stroke
				(width 0.15)
				(type solid)
			)
			(layer "F.Fab")
		)
		(fp_line
			(start 0.504 -0.25)
			(end 0.504 0.248)
			(stroke
				(width 0.15)
				(type solid)
			)
			(layer "F.Fab")
		)
		(fp_line
			(start 0.504 0.248)
			(end -0.494 0.248)
			(stroke
				(width 0.15)
				(type solid)
			)
			(layer "F.Fab")
		)
		(fp_text user "License: Apache-2.0"
			(at -0.939 5.799 0)
			(layer "F.Fab")
			(effects
				(font
					(size 0.7 0.7)
					(thickness 0.15)
				)
				(justify left bottom)
			)
		)
		(fp_text user "Author: Antmicro"
			(at -0.939 3.399 0)
			(layer "F.Fab")
			(effects
				(font
					(size 0.7 0.7)
					(thickness 0.15)
				)
				(justify left bottom)
			)
		)
		(fp_text user "${REFERENCE}"
			(at -0.939 4.599 0)
			(layer "F.Fab")
			(effects
				(font
					(size 0.7 0.7)
					(thickness 0.15)
				)
				(justify left bottom)
			)
		)
		(pad "1" smd roundrect
			(at -0.48 0)
			(size 0.59 0.64)
			(layers "F.Cu" "F.Mask" "F.Paste")
			(roundrect_rratio 0.25)
			(net 23 "GND")
			(pintype "passive")
		)
		(pad "2" smd roundrect
			(at 0.48 0)
			(size 0.59 0.64)
			(layers "F.Cu" "F.Mask" "F.Paste")
			(roundrect_rratio 0.25)
			(net 57 "+3V3_TB")
			(pintype "passive")
		)
	)
)
